# T6G (Grand Teton) — schematic netlist excerpt (pin names and nets, part order shuffled) for the footprints in the layout excerpt that follows; sources: Cadence DE-HDL packaged netlist, KiCad conversion of 04192023_DAF0TMB3IC0_F0TG_MB_C_brd_V02_OCP.brd

R1639  Q_RES  22 1% CHIP  pkg 0402LF  page 173 : A = JTAG_P0_R_TMS ; B = JTAG_CPU0_TMS
C1337  Q_CAP  0.1UF 25V 10% X7R  pkg 0402  page 159 : A = P3V3_AUX ; B = GND

(kicad_pcb
	(version 20260206)
	(generator "pcbnew")
	(generator_version "10.0")
	(general
		(thickness 1.6)
		(legacy_teardrops no)
	)
	(paper "A4")
	(title_block
		(title "04192023_DAF0TMB3IC0_F0TG_MB_C_brd_V02_OCP.brd")
		(comment 1 "Grand Teton / footprints 236-237 of 8354")
	)
	(layers
		(0 "F.Cu" signal "TOP")
		(4 "In1.Cu" signal "GND")
		(6 "In2.Cu" signal "IN1")
		(8 "In3.Cu" signal "GND1")
		(10 "In4.Cu" signal "IN2")
		(12 "In5.Cu" signal "GND2")
		(14 "In6.Cu" signal "IN3")
		(16 "In7.Cu" signal "GND3")
		(18 "In8.Cu" signal "VCC")
		(20 "In9.Cu" signal "VCC1")
		(22 "In10.Cu" signal "GND4")
		(24 "In11.Cu" signal "IN4")
		(26 "In12.Cu" signal "GND5")
		(28 "In13.Cu" signal "IN5")
		(30 "In14.Cu" signal "GND6")
		(32 "In15.Cu" signal "IN6")
		(34 "In16.Cu" signal "GND7")
		(2 "B.Cu" signal "BOTTOM")
		(9 "F.Adhes" user "F.Adhesive")
		(11 "B.Adhes" user "B.Adhesive")
		(13 "F.Paste" user "Package Geometry/Pastemask Top")
		(15 "B.Paste" user "Package Geometry/Pastemask Bottom")
		(5 "F.SilkS" user "Ref Des/Silkscreen Top")
		(7 "B.SilkS" user "Ref Des/Silkscreen Bottom")
		(1 "F.Mask" user "Board Geometry/Soldermask Top")
		(3 "B.Mask" user "Board Geometry/Soldermask Bottom")
		(17 "Dwgs.User" user "User.Drawings")
		(19 "Cmts.User" user "User.Comments")
		(21 "Eco1.User" user "User.Eco1")
		(23 "Eco2.User" user "User.Eco2")
		(25 "Edge.Cuts" user "Board Geometry/Outline")
		(27 "Margin" user)
		(31 "F.CrtYd" user "Package Geometry/Place Bound Top")
		(29 "B.CrtYd" user "Package Geometry/Place Bound Bottom")
		(35 "F.Fab" user "Ref Des/Assembly Top")
		(33 "B.Fab" user "Ref Des/Assembly Bottom")
	)
	(footprint ""
		(layer "F.Cu")
		(at 253.10084 -92.719144 -90)
		(property "Reference" "R1639"
			(at 0 0 270)
			(layer "F.SilkS")
			(hide yes)
			(effects
				(font
					(size 1.27 1.27)
				)
			)
		)
		(property "Value" ""
			(at 0 0 270)
			(layer "F.Fab")
			(effects
				(font
					(size 1.27 1.27)
				)
			)
		)
		(duplicate_pad_numbers_are_jumpers no)
		(fp_line
			(start -0.7874 0.4064)
			(end -0.7874 -0.4064)
			(stroke
				(width 0.1524)
				(type default)
			)
			(layer "F.SilkS")
		)
		(fp_line
			(start 0.7874 0.4064)
			(end -0.7874 0.4064)
			(stroke
				(width 0.1524)
				(type default)
			)
			(layer "F.SilkS")
		)
		(fp_line
			(start -0.7874 -0.4064)
			(end 0.7874 -0.4064)
			(stroke
				(width 0.1524)
				(type default)
			)
			(layer "F.SilkS")
		)
		(fp_line
			(start 0.7874 -0.4064)
			(end 0.7874 0.4064)
			(stroke
				(width 0.1524)
				(type default)
			)
			(layer "F.SilkS")
		)
		(fp_line
			(start -0.67945 0.3048)
			(end -0.67945 -0.305054)
			(stroke
				(width 0.1)
				(type default)
			)
			(layer "F.Fab")
		)
		(fp_line
			(start -0.12065 0.3048)
			(end -0.67945 0.3048)
			(stroke
				(width 0.1)
				(type default)
			)
			(layer "F.Fab")
		)
		(fp_line
			(start 0.120396 0.3048)
			(end 0.120396 0.2794)
			(stroke
				(width 0.1)
				(type default)
			)
			(layer "F.Fab")
		)
		(fp_line
			(start 0.67945 0.3048)
			(end 0.120396 0.3048)
			(stroke
				(width 0.1)
				(type default)
			)
			(layer "F.Fab")
		)
		(fp_line
			(start -0.12065 0.2794)
			(end -0.12065 0.3048)
			(stroke
				(width 0.1)
				(type default)
			)
			(layer "F.Fab")
		)
		(fp_line
			(start 0.120396 0.2794)
			(end -0.12065 0.2794)
			(stroke
				(width 0.1)
				(type default)
			)
			(layer "F.Fab")
		)
		(fp_line
			(start -0.12065 -0.2794)
			(end 0.12065 -0.2794)
			(stroke
				(width 0.1)
				(type default)
			)
			(layer "F.Fab")
		)
		(fp_line
			(start 0.12065 -0.2794)
			(end 0.12065 -0.3048)
			(stroke
				(width 0.1)
				(type default)
			)
			(layer "F.Fab")
		)
		(fp_line
			(start 0.12065 -0.3048)
			(end 0.67945 -0.3048)
			(stroke
				(width 0.1)
				(type default)
			)
			(layer "F.Fab")
		)
		(fp_line
			(start 0.67945 -0.3048)
			(end 0.67945 0.3048)
			(stroke
				(width 0.1)
				(type default)
			)
			(layer "F.Fab")
		)
		(fp_line
			(start -0.67945 -0.305054)
			(end -0.12065 -0.305054)
			(stroke
				(width 0.1)
				(type default)
			)
			(layer "F.Fab")
		)
		(fp_line
			(start -0.12065 -0.305054)
			(end -0.12065 -0.2794)
			(stroke
				(width 0.1)
				(type default)
			)
			(layer "F.Fab")
		)
		(pad "1" smd circle
			(at -0.40005 0 270)
			(size 0 0)
			(layers "F.Cu" "F.Mask" "F.Paste")
			(net "JTAG_P0_R_TMS")
		)
		(pad "2" smd circle
			(at 0.40005 0 270)
			(size 0 0)
			(layers "F.Cu" "F.Mask" "F.Paste")
			(net "JTAG_CPU0_TMS")
		)
	)
	(footprint ""
		(layer "F.Cu")
		(at 438.107836 -166.684452 180)
		(property "Reference" "C1337"
			(at 0 0 180)
			(layer "F.SilkS")
			(hide yes)
			(effects
				(font
					(size 1.27 1.27)
				)
			)
		)
		(property "Value" ""
			(at 0 0 180)
			(layer "F.Fab")
			(effects
				(font
					(size 1.27 1.27)
				)
			)
		)
		(duplicate_pad_numbers_are_jumpers no)
		(fp_line
			(start 0.7874 0.4064)
			(end -0.7874 0.4064)
			(stroke
				(width 0.1524)
				(type default)
			)
			(layer "F.SilkS")
		)
		(fp_line
			(start 0.7874 -0.4064)
			(end 0.7874 0.4064)
			(stroke
				(width 0.1524)
				(type default)
			)
			(layer "F.SilkS")
		)
		(fp_line
			(start -0.7874 0.4064)
			(end -0.7874 -0.4064)
			(stroke
				(width 0.1524)
				(type default)
			)
			(layer "F.SilkS")
		)
		(fp_line
			(start -0.7874 -0.4064)
			(end 0.7874 -0.4064)
			(stroke
				(width 0.1524)
				(type default)
			)
			(layer "F.SilkS")
		)
		(fp_line
			(start 0.67945 0.3048)
			(end 0.120396 0.3048)
			(stroke
				(width 0.1)
				(type default)
			)
			(layer "F.Fab")
		)
		(fp_line
			(start 0.67945 -0.3048)
			(end 0.67945 0.3048)
			(stroke
				(width 0.1)
				(type default)
			)
			(layer "F.Fab")
		)
		(fp_line
			(start 0.12065 -0.2794)
			(end 0.12065 -0.3048)
			(stroke
				(width 0.1)
				(type default)
			)
			(layer "F.Fab")
		)
		(fp_line
			(start 0.12065 -0.3048)
			(end 0.67945 -0.3048)
			(stroke
				(width 0.1)
				(type default)
			)
			(layer "F.Fab")
		)
		(fp_line
			(start 0.120396 0.3048)
			(end 0.120396 0.2794)
			(stroke
				(width 0.1)
				(type default)
			)
			(layer "F.Fab")
		)
		(fp_line
			(start 0.120396 0.2794)
			(end -0.12065 0.2794)
			(stroke
				(width 0.1)
				(type default)
			)
			(layer "F.Fab")
		)
		(fp_line
			(start -0.12065 0.3048)
			(end -0.67945 0.3048)
			(stroke
				(width 0.1)
				(type default)
			)
			(layer "F.Fab")
		)
		(fp_line
			(start -0.12065 0.2794)
			(end -0.12065 0.3048)
			(stroke
				(width 0.1)
				(type default)
			)
			(layer "F.Fab")
		)
		(fp_line
			(start -0.12065 -0.2794)
			(end 0.12065 -0.2794)
			(stroke
				(width 0.1)
				(type default)
			)
			(layer "F.Fab")
		)
		(fp_line
			(start -0.12065 -0.305054)
			(end -0.12065 -0.2794)
			(stroke
				(width 0.1)
				(type default)
			)
			(layer "F.Fab")
		)
		(fp_line
			(start -0.67945 0.3048)
			(end -0.67945 -0.305054)
			(stroke
				(width 0.1)
				(type default)
			)
			(layer "F.Fab")
		)
		(fp_line
			(start -0.67945 -0.305054)
			(end -0.12065 -0.305054)
			(stroke
				(width 0.1)
				(type default)
			)
			(layer "F.Fab")
		)
		(pad "1" smd circle
			(at -0.40005 0 180)
			(size 0 0)
			(layers "F.Cu" "F.Mask" "F.Paste")
			(net "P3V3_AUX")
		)
		(pad "2" smd circle
			(at 0.40005 0 180)
			(size 0 0)
			(layers "F.Cu" "F.Mask" "F.Paste")
			(net "GND")
		)
	)
)
